FILE_TYPE = CONNECTIVITY;
{Allegro Design Entry HDL 17.2-2016 S081 (4005846) 1/11/2022}
"PAGE_NUMBER" = 38;
0"NC";
1"PVCCFA_EHV_FIVRA_CPU0\g";
2"PVCCFA_EHV_FIVRA_CPU0\g";
%"VCC_CORE"
"1","(-2375,4000)","0","logical_power","I2";
;
HDL_POWER"PVCCFA_EHV_FIVRA_CPU0"
CDS_LIB"logical_power";
"A"2;
%"SOCKET4677_AZIF0045P001C01CS"
"30","(-925,2050)","0","pure_quanta","I4";
;
PART_NUMBER"DGA^7000023"
PART_TYPE"SMLF"
MATERIAL"IO"
VALUE"SOCKET4677_AZIF0045-P001C01CS"
$LOCATION"U2"
CDS_LIB"pure_quanta"
NEEDS_NO_SIZE"TRUE"
CDS_LMAN_SYM_OUTLINE"-1050,1500,1050,-1450"
CDS_LOCATION"U2"
$SEC"30"
CDS_SEC"30";
"VCCFA_EHV_FIVRA0"
$PN"AA11"1;
"VCCFA_EHV_FIVRA1"
$PN"AA15"1;
"VCCFA_EHV_FIVRA2"
$PN"AA7"1;
"VCCFA_EHV_FIVRA3"
$PN"AD85"1;
"VCCFA_EHV_FIVRA4"
$PN"AD89"1;
"VCCFA_EHV_FIVRA5"
$PN"AE11"1;
"VCCFA_EHV_FIVRA6"
$PN"AE15"1;
"VCCFA_EHV_FIVRA7"
$PN"AE7"1;
"VCCFA_EHV_FIVRA8"
$PN"AF77"1;
"VCCFA_EHV_FIVRA9"
$PN"AG78"1;
"VCCFA_EHV_FIVRA10"
$PN"AH85"1;
"VCCFA_EHV_FIVRA11"
$PN"AH89"1;
"VCCFA_EHV_FIVRA12"
$PN"AJ11"1;
"VCCFA_EHV_FIVRA13"
$PN"AJ15"1;
"VCCFA_EHV_FIVRA14"
$PN"AJ7"1;
"VCCFA_EHV_FIVRA15"
$PN"AM79"1;
"VCCFA_EHV_FIVRA16"
$PN"AM85"1;
"VCCFA_EHV_FIVRA17"
$PN"AM89"1;
"VCCFA_EHV_FIVRA18"
$PN"AN11"1;
"VCCFA_EHV_FIVRA19"
$PN"AN15"1;
"VCCFA_EHV_FIVRA20"
$PN"AN7"1;
"VCCFA_EHV_FIVRA21"
$PN"AN80"1;
"VCCFA_EHV_FIVRA22"
$PN"AT73"1;
"VCCFA_EHV_FIVRA23"
$PN"AT89"1;
"VCCFA_EHV_FIVRA24"
$PN"AU15"1;
"VCCFA_EHV_FIVRA25"
$PN"AW76"1;
"VCCFA_EHV_FIVRA26"
$PN"AY89"1;
"VCCFA_EHV_FIVRA27"
$PN"BE72"1;
"VCCFA_EHV_FIVRA28"
$PN"BF77"1;
"VCCFA_EHV_FIVRA29"
$PN"BH79"1;
"VCCFA_EHV_FIVRA30"
$PN"BJ72"1;
"VCCFA_EHV_FIVRA31"
$PN"BJ78"2;
"VCCFA_EHV_FIVRA32"
$PN"C84"1;
"VCCFA_EHV_FIVRA33"
$PN"C88"1;
"VCCFA_EHV_FIVRA34"
$PN"CE74"2;
"VCCFA_EHV_FIVRA35"
$PN"CK73"2;
"VCCFA_EHV_FIVRA36"
$PN"CK79"2;
"VCCFA_EHV_FIVRA37"
$PN"CM73"2;
"VCCFA_EHV_FIVRA38"
$PN"CN78"2;
"VCCFA_EHV_FIVRA39"
$PN"CP73"2;
"VCCFA_EHV_FIVRA40"
$PN"CT77"2;
"VCCFA_EHV_FIVRA41"
$PN"CT85"2;
"VCCFA_EHV_FIVRA42"
$PN"CY75"2;
"VCCFA_EHV_FIVRA43"
$PN"CY79"2;
"VCCFA_EHV_FIVRA44"
$PN"CY85"2;
"VCCFA_EHV_FIVRA45"
$PN"CY89"2;
"VCCFA_EHV_FIVRA46"
$PN"DD77"2;
"VCCFA_EHV_FIVRA47"
$PN"DD83"2;
"VCCFA_EHV_FIVRA48"
$PN"DD85"2;
"VCCFA_EHV_FIVRA49"
$PN"DD89"2;
"VCCFA_EHV_FIVRA50"
$PN"DH89"2;
"VCCFA_EHV_FIVRA51"
$PN"DM83"2;
"VCCFA_EHV_FIVRA52"
$PN"DM85"2;
"VCCFA_EHV_FIVRA53"
$PN"DM89"2;
"VCCFA_EHV_FIVRA54"
$PN"DN11"2;
"VCCFA_EHV_FIVRA55"
$PN"DN15"2;
"VCCFA_EHV_FIVRA56"
$PN"DN3"2;
"VCCFA_EHV_FIVRA57"
$PN"DN7"2;
"VCCFA_EHV_FIVRA58"
$PN"DT79"2;
"VCCFA_EHV_FIVRA59"
$PN"DT85"2;
"VCCFA_EHV_FIVRA60"
$PN"DT89"2;
"VCCFA_EHV_FIVRA61"
$PN"DU11"2;
"VCCFA_EHV_FIVRA62"
$PN"DU15"2;
"VCCFA_EHV_FIVRA63"
$PN"DU3"2;
"VCCFA_EHV_FIVRA64"
$PN"DU7"2;
"VCCFA_EHV_FIVRA65"
$PN"DY85"2;
"VCCFA_EHV_FIVRA66"
$PN"DY89"2;
"VCCFA_EHV_FIVRA67"
$PN"EA11"2;
"VCCFA_EHV_FIVRA68"
$PN"EA15"2;
"VCCFA_EHV_FIVRA69"
$PN"EA3"2;
"VCCFA_EHV_FIVRA70"
$PN"EA7"2;
"VCCFA_EHV_FIVRA71"
$PN"EC78"2;
"VCCFA_EHV_FIVRA72"
$PN"ED79"2;
"VCCFA_EHV_FIVRA73"
$PN"ED85"2;
"VCCFA_EHV_FIVRA74"
$PN"ED89"2;
"VCCFA_EHV_FIVRA75"
$PN"EE11"2;
"VCCFA_EHV_FIVRA76"
$PN"EE15"2;
"VCCFA_EHV_FIVRA77"
$PN"EE7"2;
"VCCFA_EHV_FIVRA78"
$PN"EE84"2;
"VCCFA_EHV_FIVRA79"
$PN"EF79"2;
"VCCFA_EHV_FIVRA80"
$PN"EG80"2;
"VCCFA_EHV_FIVRA81"
$PN"EJ15"2;
"VCCFA_EHV_FIVRA82"
$PN"EJ84"2;
"VCCFA_EHV_FIVRA83"
$PN"EN84"2;
"VCCFA_EHV_FIVRA84"
$PN"H89"1;
"VCCFA_EHV_FIVRA85"
$PN"J11"1;
"VCCFA_EHV_FIVRA86"
$PN"J7"1;
"VCCFA_EHV_FIVRA87"
$PN"J80"1;
"VCCFA_EHV_FIVRA88"
$PN"K87"1;
"VCCFA_EHV_FIVRA89"
$PN"L84"1;
"VCCFA_EHV_FIVRA90"
$PN"M85"1;
"VCCFA_EHV_FIVRA91"
$PN"M89"1;
"VCCFA_EHV_FIVRA92"
$PN"N11"1;
"VCCFA_EHV_FIVRA93"
$PN"N7"1;
"VCCFA_EHV_FIVRA94"
$PN"P79"1;
"VCCFA_EHV_FIVRA95"
$PN"R80"1;
"VCCFA_EHV_FIVRA96"
$PN"T85"1;
"VCCFA_EHV_FIVRA97"
$PN"T89"1;
"VCCFA_EHV_FIVRA98"
$PN"U11"1;
"VCCFA_EHV_FIVRA99"
$PN"U15"1;
"VCCFA_EHV_FIVRA100"
$PN"U7"1;
"VCCFA_EHV_FIVRA101"
$PN"W80"1;
"VCCFA_EHV_FIVRA102"
$PN"Y79"1;
"VCCFA_EHV_FIVRA103"
$PN"Y85"1;
"VCCFA_EHV_FIVRA104"
$PN"Y89"1;
%"VCC_CORE"
"1","(525,4000)","0","logical_power","I5";
;
HDL_POWER"PVCCFA_EHV_FIVRA_CPU0"
CDS_LIB"logical_power";
"A"1;
END.
